(kicad_pcb
	(version 20221018)
	(generator pcbnew)
	(general
    (thickness 1.62)
  )
	(paper "A4")
	(title_block
    (title "ECP5 - Datacenter Secure Control Module (DC-SCM)")
    (date "2024-07-01")
    (rev "1.2.1")
		(comment 9 "footprints 16-24 of 506")
	)
	(layers
    (0 "F.Cu" signal)
    (1 "In1.Cu" power)
    (2 "In2.Cu" signal)
    (3 "In3.Cu" power)
    (4 "In4.Cu" power)
    (5 "In5.Cu" signal)
    (6 "In6.Cu" power)
    (31 "B.Cu" signal)
    (32 "B.Adhes" user "B.Adhesive")
    (33 "F.Adhes" user "F.Adhesive")
    (34 "B.Paste" user)
    (35 "F.Paste" user)
    (36 "B.SilkS" user "B.Silkscreen")
    (37 "F.SilkS" user "F.Silkscreen")
    (38 "B.Mask" user)
    (39 "F.Mask" user)
    (40 "Dwgs.User" user "User.Drawings")
    (41 "Cmts.User" user "User.Comments")
    (42 "Eco1.User" user "User.Eco1")
    (43 "Eco2.User" user "User.Eco2")
    (44 "Edge.Cuts" user)
    (45 "Margin" user)
    (46 "B.CrtYd" user "B.Courtyard")
    (47 "F.CrtYd" user "F.Courtyard")
    (48 "B.Fab" user)
    (49 "F.Fab" user)
  )
	(footprint "antmicro-footprints:C_0402_1005Metric" (layer "F.Cu")
    (at 71.4 119.6 90)
    (descr "Capacitor SMD 0402")
    (tags "capacitor SMD 0402")
    (property "Author" "Antmicro")
    (property "Dielectric" "")
    (property "License" "Apache-2.0")
    (property "MPN" "CC0402MRX5R5BB106")
    (property "Manufacturer" "YAGEO")
    (property "Public" "False")
    (property "Sheetfile" "ddr3.kicad_sch")
    (property "Sheetname" "DDR3")
    (property "Val" "10u")
    (property "Voltage" "")
    (property "ki_description" "SMD Multilayer Ceramic Capacitor, 10 µF, 6.3 V, 0402 [1005 Metric], ± 20%, X5R, CC Series")
    (property "ki_keywords" "0402, SMT, CAPACITOR, PASSIVE, MLCC, CERAMIC")
    (attr smd)
    (fp_text reference "C78" (at 0.155 -1.01 90) (layer "F.SilkS")
        (effects (font (size 0.7 0.7) (thickness 0.127)))
    )
    (fp_text value "C_10u_0402" (at 0 1.17 90) (layer "F.Fab")
        (effects (font (size 1 1) (thickness 0.15)))
    )
    (fp_text user "${REFERENCE}" (at 0 0 90) (layer "F.Fab")
        (effects (font (size 0.25 0.25) (thickness 0.04)))
    )
    (fp_text user "Author: Antmicro" (at -0.939 3.399 90) (layer "F.Fab") hide
        (effects (font (size 0.7 0.7) (thickness 0.15)) (justify left bottom))
    )
    (fp_text user "License: Apache-2.0" (at -0.939 5.799 90) (layer "F.Fab") hide
        (effects (font (size 0.7 0.7) (thickness 0.15)) (justify left bottom))
    )
    (fp_rect (start -0.925 -0.47) (end 0.925 0.47)
      (stroke (width 0.05) (type default)) (fill none) (layer "F.CrtYd"))
    (fp_line (start -0.494 -0.25) (end 0.504 -0.25)
      (stroke (width 0.15) (type solid)) (layer "F.Fab"))
    (fp_line (start -0.494 0.248) (end -0.494 -0.25)
      (stroke (width 0.15) (type solid)) (layer "F.Fab"))
    (fp_line (start 0.504 -0.25) (end 0.504 0.248)
      (stroke (width 0.15) (type solid)) (layer "F.Fab"))
    (fp_line (start 0.504 0.248) (end -0.494 0.248)
      (stroke (width 0.15) (type solid)) (layer "F.Fab"))
    (pad "1" smd roundrect (at -0.48 0 90) (size 0.59 0.64) (layers "F.Cu" "F.Paste" "F.Mask") (roundrect_rratio 0.25)
      (net 1 "GND") (pintype "passive"))
    (pad "2" smd roundrect (at 0.48 0 90) (size 0.59 0.64) (layers "F.Cu" "F.Paste" "F.Mask") (roundrect_rratio 0.25)
      (net 2 "VCC3V3") (pintype "passive"))
  )
	(footprint "antmicro-footprints:R_0402_1005Metric" (layer "F.Cu")
    (at 91.3 78.35 90)
    (descr "Resistor SMD 0402")
    (tags "resistor SMD 0402")
    (property "Author" "Antmicro")
    (property "License" "Apache-2.0")
    (property "MPN" "CR0402-FX-4703GLF")
    (property "Manufacturer" "Bourns")
    (property "Public" "False")
    (property "Sheetfile" "power-supply.kicad_sch")
    (property "Sheetname" "Power supply")
    (property "Tolerance" "1%")
    (property "Val" "470k")
    (property "ki_description" "SMD Chip Resistor, 470 kohm, ± 1%, 62.5 mW, 0402 [1005 Metric], Thick Film, Sulfur Resistant")
    (property "ki_keywords" "0402, SMT, RESISTOR, PASSIVE")
    (attr smd)
    (fp_text reference "R99" (at -4.795 3.26 90) (layer "F.SilkS")
        (effects (font (size 0.7 0.7) (thickness 0.127)))
    )
    (fp_text value "R_470k_0402" (at 0 1.17 90) (layer "F.Fab")
        (effects (font (size 1 1) (thickness 0.15)))
    )
    (fp_text user "${REFERENCE}" (at 0 0 90) (layer "F.Fab")
        (effects (font (size 0.25 0.25) (thickness 0.04)))
    )
    (fp_text user "Author: Antmicro" (at -0.95 4.169 90) (layer "F.Fab") hide
        (effects (font (size 0.7 0.7) (thickness 0.15)) (justify left bottom))
    )
    (fp_text user "License: Apache-2.0" (at -0.95 5.169 90) (layer "F.Fab") hide
        (effects (font (size 0.7 0.7) (thickness 0.15)) (justify left bottom))
    )
    (fp_rect (start -0.925 -0.47) (end 0.925 0.47)
      (stroke (width 0.05) (type default)) (fill none) (layer "F.CrtYd"))
    (fp_rect (start -0.5 -0.25) (end 0.5 0.25)
      (stroke (width 0.15) (type solid)) (fill none) (layer "F.Fab"))
    (pad "1" smd roundrect (at -0.48 0 90) (size 0.59 0.64) (layers "F.Cu" "F.Paste" "F.Mask") (roundrect_rratio 0.25)
      (net 368 "Net-(C108-Pad1)") (pintype "passive"))
    (pad "2" smd roundrect (at 0.48 0 90) (size 0.59 0.64) (layers "F.Cu" "F.Paste" "F.Mask") (roundrect_rratio 0.25)
      (net 289 "Net-(U13-FB)") (pintype "passive"))
  )
	(footprint "antmicro-footprints:R_0402_1005Metric" (layer "F.Cu")
    (at 91.8 76.85)
    (descr "Resistor SMD 0402")
    (tags "resistor SMD 0402")
    (property "Author" "Antmicro")
    (property "License" "Apache-2.0")
    (property "MPN" "CR0402-FX-1002GLF")
    (property "Manufacturer" "Bourns")
    (property "Public" "False")
    (property "Sheetfile" "power-supply.kicad_sch")
    (property "Sheetname" "Power supply")
    (property "Tolerance" "1%")
    (property "Val" "10k")
    (property "ki_description" "SMD Chip Resistor, 10 kohm, ± 1%, 62.5 mW, 0402 [1005 Metric], Thick Film, General Purpose")
    (property "ki_keywords" "0402, SMT, RESISTOR, PASSIVE")
    (attr smd)
    (fp_text reference "R98" (at 2.11 3.145) (layer "F.SilkS")
        (effects (font (size 0.7 0.7) (thickness 0.127)))
    )
    (fp_text value "R_10k_0402" (at 0 1.17) (layer "F.Fab")
        (effects (font (size 1 1) (thickness 0.15)))
    )
    (fp_text user "License: Apache-2.0" (at -0.95 5.169) (layer "F.Fab") hide
        (effects (font (size 0.7 0.7) (thickness 0.15)) (justify left bottom))
    )
    (fp_text user "Author: Antmicro" (at -0.95 4.169) (layer "F.Fab") hide
        (effects (font (size 0.7 0.7) (thickness 0.15)) (justify left bottom))
    )
    (fp_text user "${REFERENCE}" (at 0 0) (layer "F.Fab")
        (effects (font (size 0.25 0.25) (thickness 0.04)))
    )
    (fp_rect (start -0.925 -0.47) (end 0.925 0.47)
      (stroke (width 0.05) (type default)) (fill none) (layer "F.CrtYd"))
    (fp_rect (start -0.5 -0.25) (end 0.5 0.25)
      (stroke (width 0.15) (type solid)) (fill none) (layer "F.Fab"))
    (pad "1" smd roundrect (at -0.48 0) (size 0.59 0.64) (layers "F.Cu" "F.Paste" "F.Mask") (roundrect_rratio 0.25)
      (net 354 "Net-(C108-Pad2)") (pintype "passive"))
    (pad "2" smd roundrect (at 0.48 0) (size 0.59 0.64) (layers "F.Cu" "F.Paste" "F.Mask") (roundrect_rratio 0.25)
      (net 289 "Net-(U13-FB)") (pintype "passive"))
  )
	(footprint "antmicro-footprints:R_0402_1005Metric" (layer "F.Cu")
    (at 94.2 61.75 90)
    (descr "Resistor SMD 0402")
    (tags "resistor SMD 0402")
    (property "Author" "Antmicro")
    (property "License" "Apache-2.0")
    (property "MPN" "CR0402-FX-4702GLF")
    (property "Manufacturer" "Bourns")
    (property "Public" "False")
    (property "Sheetfile" "power-supply.kicad_sch")
    (property "Sheetname" "Power supply")
    (property "Tolerance" "1%")
    (property "Val" "47k")
    (property "ki_description" "SMD Chip Resistor, 47 kohm, ± 1%, 62.5 mW, 0402 [1005 Metric], Thick Film, General Purpose")
    (property "ki_keywords" "0402, SMT, RESISTOR, PASSIVE")
    (attr smd)
    (fp_text reference "R89" (at 0.115 1.73 90) (layer "F.SilkS")
        (effects (font (size 0.7 0.7) (thickness 0.127)))
    )
    (fp_text value "R_47k_0402" (at 0 1.17 90) (layer "F.Fab")
        (effects (font (size 1 1) (thickness 0.15)))
    )
    (fp_text user "License: Apache-2.0" (at -0.95 5.169 90) (layer "F.Fab") hide
        (effects (font (size 0.7 0.7) (thickness 0.15)) (justify left bottom))
    )
    (fp_text user "Author: Antmicro" (at -0.95 4.169 90) (layer "F.Fab") hide
        (effects (font (size 0.7 0.7) (thickness 0.15)) (justify left bottom))
    )
    (fp_text user "${REFERENCE}" (at 0 0 90) (layer "F.Fab")
        (effects (font (size 0.25 0.25) (thickness 0.04)))
    )
    (fp_rect (start -0.925 -0.47) (end 0.925 0.47)
      (stroke (width 0.05) (type default)) (fill none) (layer "F.CrtYd"))
    (fp_rect (start -0.5 -0.25) (end 0.5 0.25)
      (stroke (width 0.15) (type solid)) (fill none) (layer "F.Fab"))
    (pad "1" smd roundrect (at -0.48 0 90) (size 0.59 0.64) (layers "F.Cu" "F.Paste" "F.Mask") (roundrect_rratio 0.25)
      (net 423 "Net-(U13-FADJ)") (pintype "passive"))
    (pad "2" smd roundrect (at 0.48 0 90) (size 0.59 0.64) (layers "F.Cu" "F.Paste" "F.Mask") (roundrect_rratio 0.25)
      (net 1 "GND") (pintype "passive"))
  )
	(footprint "antmicro-footprints:C_1210_3225Metric" (layer "F.Cu")
    (at 92 74.25 180)
    (descr "Capacitor SMD 1210")
    (tags "capacitor SMD 1210")
    (property "Author" "Antmicro")
    (property "Dielectric" "")
    (property "License" "Apache-2.0")
    (property "MPN" "C1210C476K8RACTU")
    (property "Manufacturer" "KEMET")
    (property "Public" "False")
    (property "Sheetfile" "power-supply.kicad_sch")
    (property "Sheetname" "Power supply")
    (property "Val" "47u")
    (property "Voltage" "")
    (property "ki_description" "SMD Multilayer Ceramic Capacitor, 47 µF, 10 V, 1210 [3225 Metric], ± 10%, X7R, C Series KEMET")
    (property "ki_keywords" "1210, SMT, CAPACITOR, PASSIVE")
    (attr smd)
    (fp_text reference "C109" (at -6.57 0.125 90) (layer "F.SilkS")
        (effects (font (size 0.7 0.7) (thickness 0.127)))
    )
    (fp_text value "C_47u_1210" (at 0 2.8) (layer "F.Fab")
        (effects (font (size 1 1) (thickness 0.15)))
    )
    (fp_text user "${REFERENCE}" (at 0 0) (layer "F.Fab")
        (effects (font (size 0.5 0.5) (thickness 0.05)))
    )
    (fp_text user "Author: Antmicro" (at -2.1 5.749 180) (layer "F.Fab") hide
        (effects (font (size 0.7 0.7) (thickness 0.15)) (justify left bottom))
    )
    (fp_text user "License: Apache-2.0" (at -2.1 6.749 180) (layer "F.Fab") hide
        (effects (font (size 0.7 0.7) (thickness 0.15)) (justify left bottom))
    )
    (fp_line (start -0.3 -1.39) (end 0.3 -1.39)
      (stroke (width 0.15) (type solid)) (layer "F.SilkS"))
    (fp_line (start -0.3 1.39) (end 0.3 1.39)
      (stroke (width 0.15) (type solid)) (layer "F.SilkS"))
    (fp_rect (start -2.1 -1.75) (end 2.1 1.75)
      (stroke (width 0.05) (type solid)) (fill none) (layer "F.CrtYd"))
    (fp_rect (start -1.6 -1.25) (end 1.6 1.25)
      (stroke (width 0.15) (type solid)) (fill none) (layer "F.Fab"))
    (pad "1" smd rect (at -1.145 0 180) (size 1.52 3.05) (layers "F.Cu" "F.Paste" "F.Mask")
      (net 1 "GND") (pintype "passive"))
    (pad "2" smd rect (at 1.145 0 180) (size 1.52 3.05) (layers "F.Cu" "F.Paste" "F.Mask")
      (net 354 "Net-(C108-Pad2)") (pintype "passive"))
  )
	(footprint "antmicro-footprints:C_0402_1005Metric" (layer "F.Cu")
    (at 90.3 77.4 90)
    (descr "Capacitor SMD 0402")
    (tags "capacitor SMD 0402")
    (property "Author" "Antmicro")
    (property "Dielectric" "")
    (property "License" "Apache-2.0")
    (property "MPN" "C0402C751J5GACTU")
    (property "Manufacturer" "KEMET")
    (property "Public" "False")
    (property "Sheetfile" "power-supply.kicad_sch")
    (property "Sheetname" "Power supply")
    (property "Val" "750p")
    (property "Voltage" "")
    (property "ki_description" "SMD Multilayer Ceramic Capacitor, 750 pF, 50 V, 0402 [1005 Metric], ± 5%, C0G / NP0")
    (property "ki_keywords" "0402, SMT, CAPACITOR, PASSIVE, CERAMIC, MLCC")
    (attr smd)
    (fp_text reference "C108" (at 0.755 -3.35 90) (layer "F.SilkS")
        (effects (font (size 0.7 0.7) (thickness 0.127)))
    )
    (fp_text value "C_750p_0402" (at 0 1.17 90) (layer "F.Fab")
        (effects (font (size 1 1) (thickness 0.15)))
    )
    (fp_text user "License: Apache-2.0" (at -0.939 5.799 90) (layer "F.Fab") hide
        (effects (font (size 0.7 0.7) (thickness 0.15)) (justify left bottom))
    )
    (fp_text user "Author: Antmicro" (at -0.939 3.399 90) (layer "F.Fab") hide
        (effects (font (size 0.7 0.7) (thickness 0.15)) (justify left bottom))
    )
    (fp_text user "${REFERENCE}" (at 0 0 90) (layer "F.Fab")
        (effects (font (size 0.25 0.25) (thickness 0.04)))
    )
    (fp_rect (start -0.925 -0.47) (end 0.925 0.47)
      (stroke (width 0.05) (type default)) (fill none) (layer "F.CrtYd"))
    (fp_line (start -0.494 -0.25) (end 0.504 -0.25)
      (stroke (width 0.15) (type solid)) (layer "F.Fab"))
    (fp_line (start -0.494 0.248) (end -0.494 -0.25)
      (stroke (width 0.15) (type solid)) (layer "F.Fab"))
    (fp_line (start 0.504 -0.25) (end 0.504 0.248)
      (stroke (width 0.15) (type solid)) (layer "F.Fab"))
    (fp_line (start 0.504 0.248) (end -0.494 0.248)
      (stroke (width 0.15) (type solid)) (layer "F.Fab"))
    (pad "1" smd roundrect (at -0.48 0 90) (size 0.59 0.64) (layers "F.Cu" "F.Paste" "F.Mask") (roundrect_rratio 0.25)
      (net 368 "Net-(C108-Pad1)") (pintype "passive"))
    (pad "2" smd roundrect (at 0.48 0 90) (size 0.59 0.64) (layers "F.Cu" "F.Paste" "F.Mask") (roundrect_rratio 0.25)
      (net 354 "Net-(C108-Pad2)") (pintype "passive"))
  )
	(footprint "antmicro-footprints:C_0402_1005Metric" (layer "F.Cu")
    (at 92.8 77.9 180)
    (descr "Capacitor SMD 0402")
    (tags "capacitor SMD 0402")
    (property "Author" "Antmicro")
    (property "Dielectric" "")
    (property "License" "Apache-2.0")
    (property "MPN" "04025A181JAT2A")
    (property "Manufacturer" "AVX")
    (property "Public" "False")
    (property "Sheetfile" "power-supply.kicad_sch")
    (property "Sheetname" "Power supply")
    (property "Val" "180p")
    (property "Voltage" "")
    (property "ki_description" "SMD Multilayer Ceramic Capacitor, 180 pF, 50 V, 0402 [1005 Metric], ± 5%, C0G / NP0, AVX 0402 MLCC")
    (property "ki_keywords" "0402, SMT, CAPACITOR, PASSIVE, CERAMIC, MLCC")
    (attr smd)
    (fp_text reference "C107" (at -1.8 -2.935) (layer "F.SilkS")
        (effects (font (size 0.7 0.7) (thickness 0.127)))
    )
    (fp_text value "C_180p_0402" (at 0 1.17) (layer "F.Fab")
        (effects (font (size 1 1) (thickness 0.15)))
    )
    (fp_text user "Author: Antmicro" (at -0.939 3.399 180) (layer "F.Fab") hide
        (effects (font (size 0.7 0.7) (thickness 0.15)) (justify left bottom))
    )
    (fp_text user "License: Apache-2.0" (at -0.939 5.799 180) (layer "F.Fab") hide
        (effects (font (size 0.7 0.7) (thickness 0.15)) (justify left bottom))
    )
    (fp_text user "${REFERENCE}" (at 0 0) (layer "F.Fab")
        (effects (font (size 0.25 0.25) (thickness 0.04)))
    )
    (fp_rect (start -0.925 -0.47) (end 0.925 0.47)
      (stroke (width 0.05) (type default)) (fill none) (layer "F.CrtYd"))
    (fp_line (start -0.494 -0.25) (end 0.504 -0.25)
      (stroke (width 0.15) (type solid)) (layer "F.Fab"))
    (fp_line (start -0.494 0.248) (end -0.494 -0.25)
      (stroke (width 0.15) (type solid)) (layer "F.Fab"))
    (fp_line (start 0.504 -0.25) (end 0.504 0.248)
      (stroke (width 0.15) (type solid)) (layer "F.Fab"))
    (fp_line (start 0.504 0.248) (end -0.494 0.248)
      (stroke (width 0.15) (type solid)) (layer "F.Fab"))
    (pad "1" smd roundrect (at -0.48 0 180) (size 0.59 0.64) (layers "F.Cu" "F.Paste" "F.Mask") (roundrect_rratio 0.25)
      (net 267 "Net-(U13-COMP)") (pintype "passive"))
    (pad "2" smd roundrect (at 0.48 0 180) (size 0.59 0.64) (layers "F.Cu" "F.Paste" "F.Mask") (roundrect_rratio 0.25)
      (net 289 "Net-(U13-FB)") (pintype "passive"))
  )
	(footprint "antmicro-footprints:C_0402_1005Metric" (layer "F.Cu")
    (at 94.3 78.35 -90)
    (descr "Capacitor SMD 0402")
    (tags "capacitor SMD 0402")
    (property "Author" "Antmicro")
    (property "Dielectric" "")
    (property "License" "Apache-2.0")
    (property "MPN" "0402B182K500CT")
    (property "Manufacturer" "Walsin")
    (property "Public" "False")
    (property "Sheetfile" "power-supply.kicad_sch")
    (property "Sheetname" "Power supply")
    (property "Val" "1n8")
    (property "Voltage" "")
    (property "ki_description" "SMD Multilayer Ceramic Capacitor, General Purpose, 1800 pF, 50 V, 0402 [1005 Metric], ± 10%, X7R")
    (property "ki_keywords" "0402, SMT, CAPACITOR, PASSIVE, MLCC")
    (attr smd)
    (fp_text reference "C106" (at 3.555 -1.98 90) (layer "F.SilkS")
        (effects (font (size 0.7 0.7) (thickness 0.127)))
    )
    (fp_text value "C_1n8_0402" (at 0 1.17 90) (layer "F.Fab")
        (effects (font (size 1 1) (thickness 0.15)))
    )
    (fp_text user "Author: Antmicro" (at -0.939 3.399 -90) (layer "F.Fab") hide
        (effects (font (size 0.7 0.7) (thickness 0.15)) (justify left bottom))
    )
    (fp_text user "${REFERENCE}" (at 0 0 90) (layer "F.Fab")
        (effects (font (size 0.25 0.25) (thickness 0.04)))
    )
    (fp_text user "License: Apache-2.0" (at -0.939 5.799 -90) (layer "F.Fab") hide
        (effects (font (size 0.7 0.7) (thickness 0.15)) (justify left bottom))
    )
    (fp_rect (start -0.925 -0.47) (end 0.925 0.47)
      (stroke (width 0.05) (type default)) (fill none) (layer "F.CrtYd"))
    (fp_line (start -0.494 -0.25) (end 0.504 -0.25)
      (stroke (width 0.15) (type solid)) (layer "F.Fab"))
    (fp_line (start -0.494 0.248) (end -0.494 -0.25)
      (stroke (width 0.15) (type solid)) (layer "F.Fab"))
    (fp_line (start 0.504 -0.25) (end 0.504 0.248)
      (stroke (width 0.15) (type solid)) (layer "F.Fab"))
    (fp_line (start 0.504 0.248) (end -0.494 0.248)
      (stroke (width 0.15) (type solid)) (layer "F.Fab"))
    (pad "1" smd roundrect (at -0.48 0 270) (size 0.59 0.64) (layers "F.Cu" "F.Paste" "F.Mask") (roundrect_rratio 0.25)
      (net 267 "Net-(U13-COMP)") (pintype "passive"))
    (pad "2" smd roundrect (at 0.48 0 270) (size 0.59 0.64) (layers "F.Cu" "F.Paste" "F.Mask") (roundrect_rratio 0.25)
      (net 352 "Net-(C106-Pad2)") (pintype "passive"))
  )
	(footprint "antmicro-footprints:L_Coilcraft-XAL5030" (layer "F.Cu")
    (at 86.5 75.25)
    (property "Author" "Antmicro")
    (property "IMax" "13 A")
    (property "ISat" "18.5 A")
    (property "License" "Apache-2.0")
    (property "MPN" "XAL5030-801MEC")
    (property "Manufacturer" "Coilcraft")
    (property "Public" "False")
    (property "Sheetfile" "power-supply.kicad_sch")
    (property "Sheetname" "Power supply")
    (property "Size" "5.28x5.48")
    (property "Val" "800n/13A")
    (property "ki_description" "Power Inductor (SMD), 800 nH, 13 A, Shielded, 18.5 A, XAL5030")
    (property "ki_keywords" "SMT, INDUCTOR, PASSIVE")
    (attr smd)
    (fp_text reference "L1" (at 0.55 -3.4) (layer "F.SilkS")
        (effects (font (size 0.7 0.7) (thickness 0.127)) (justify left))
    )
    (fp_text value "XAL5030-801" (at -0.4318 4.2418) (layer "F.Fab")
        (effects (font (size 1.27 1.27) (thickness 0.15)))
    )
    (fp_text user "License: Apache-2.0" (at -2.89 6.241) (layer "F.Fab") hide
        (effects (font (size 0.7 0.7) (thickness 0.15)) (justify left bottom))
    )
    (fp_text user "Author: Antmicro" (at -2.89 7.441) (layer "F.Fab") hide
        (effects (font (size 0.7 0.7) (thickness 0.15)) (justify left bottom))
    )
    (fp_text user "${REFERENCE}" (at -2.89 8.641) (layer "F.Fab") hide
        (effects (font (size 0.7 0.7) (thickness 0.15)) (justify left bottom))
    )
    (fp_line (start -2.74 -2.84) (end 2.74 -2.84)
      (stroke (width 0.15) (type solid)) (layer "F.SilkS"))
    (fp_line (start -2.74 2.84) (end -2.74 -2.84)
      (stroke (width 0.15) (type solid)) (layer "F.SilkS"))
    (fp_line (start -2.74 2.84) (end 2.74 2.84)
      (stroke (width 0.15) (type solid)) (layer "F.SilkS"))
    (fp_line (start 2.74 2.84) (end 2.74 -2.84)
      (stroke (width 0.15) (type solid)) (layer "F.SilkS"))
    (fp_rect (start -2.89 -2.99) (end 2.89 2.99)
      (stroke (width 0.05) (type solid)) (fill none) (layer "F.CrtYd"))
    (fp_line (start -2.74 -2.84) (end 2.74 -2.84)
      (stroke (width 0.15) (type solid)) (layer "F.Fab"))
    (fp_line (start -2.74 2.84) (end -2.74 -2.84)
      (stroke (width 0.15) (type solid)) (layer "F.Fab"))
    (fp_line (start 2.74 -2.84) (end 2.74 2.84)
      (stroke (width 0.15) (type solid)) (layer "F.Fab"))
    (fp_line (start 2.74 2.84) (end -2.74 2.84)
      (stroke (width 0.15) (type solid)) (layer "F.Fab"))
    (pad "1" smd roundrect (at -1.655 0) (size 1.18 4.7) (layers "F.Cu" "F.Paste" "F.Mask") (roundrect_rratio 0.1)
      (net 234 "Net-(L1-Pad1)") (pintype "passive"))
    (pad "2" smd roundrect (at 1.655 0) (size 1.18 4.7) (layers "F.Cu" "F.Paste" "F.Mask") (roundrect_rratio 0.1)
      (net 354 "Net-(C108-Pad2)") (pintype "passive"))
  )
)
